(kicad_pcb
	(version 20241229)
	(generator "pcbnew")
	(generator_version "9.0")
	(general
		(thickness 1.294)
		(legacy_teardrops no)
	)
	(paper "A3")
	(title_block
		(title "Kintex 410T devboard")
		(date "2024-04-03")
		(rev "1.1.2")
		(comment 9 "footprints 795-800 of 975")
	)
	(layers
		(0 "F.Cu" mixed)
		(4 "In1.Cu" power)
		(6 "In2.Cu" power)
		(8 "In3.Cu" mixed)
		(10 "In4.Cu" power)
		(12 "In5.Cu" mixed)
		(14 "In6.Cu" power)
		(16 "In7.Cu" mixed)
		(18 "In8.Cu" power)
		(2 "B.Cu" mixed)
		(9 "F.Adhes" user "F.Adhesive")
		(11 "B.Adhes" user "B.Adhesive")
		(13 "F.Paste" user)
		(15 "B.Paste" user)
		(5 "F.SilkS" user "F.Silkscreen")
		(7 "B.SilkS" user "B.Silkscreen")
		(1 "F.Mask" user)
		(3 "B.Mask" user)
		(17 "Dwgs.User" user "User.Drawings")
		(19 "Cmts.User" user "User.Comments")
		(21 "Eco1.User" user "User.Eco1")
		(23 "Eco2.User" user "User.Eco2")
		(25 "Edge.Cuts" user)
		(27 "Margin" user)
		(31 "F.CrtYd" user "F.Courtyard")
		(29 "B.CrtYd" user "B.Courtyard")
		(35 "F.Fab" user)
		(33 "B.Fab" user)
	)
	(footprint "antmicro-footprints:R_0402_1005Metric"
		(layer "B.Cu")
		(at 244.701 166 180)
		(descr "Resistor SMD 0402")
		(tags "resistor SMD 0402")
		(property "Reference" "R243"
			(at -1.349 -2.25 180)
			(layer "B.SilkS")
			(effects
				(font
					(size 0.7 0.7)
					(thickness 0.15)
				)
				(justify left bottom mirror)
			)
		)
		(property "Value" "R_0R_0402"
			(at 0 -1.4 0)
			(layer "B.Fab")
			(effects
				(font
					(size 0.7 0.7)
					(thickness 0.15)
				)
				(justify left bottom mirror)
			)
		)
		(property "Description" "SMD Chip Resistor, Jumper, 0 ohm, 100 mW, 0402 [1005 Metric], Thick Film, General Purpose"
			(at 0 0 180)
			(layer "F.Fab")
			(hide yes)
			(effects
				(font
					(size 1.27 1.27)
					(thickness 0.15)
				)
			)
		)
		(property "Author" "Antmicro"
			(at 489.402 332 0)
			(layer "B.Fab")
			(hide yes)
			(effects
				(font
					(size 1 1)
					(thickness 0.15)
				)
				(justify mirror)
			)
		)
		(property "Current" "1A"
			(at 489.402 332 0)
			(layer "B.Fab")
			(hide yes)
			(effects
				(font
					(size 1 1)
					(thickness 0.15)
				)
				(justify mirror)
			)
		)
		(property "License" "Apache-2.0"
			(at 489.402 332 0)
			(layer "B.Fab")
			(hide yes)
			(effects
				(font
					(size 1 1)
					(thickness 0.15)
				)
				(justify mirror)
			)
		)
		(property "MPN" "ERJ2GE0R00X"
			(at 489.402 332 0)
			(layer "B.Fab")
			(hide yes)
			(effects
				(font
					(size 1 1)
					(thickness 0.15)
				)
				(justify mirror)
			)
		)
		(property "Manufacturer" "Panasonic"
			(at 489.402 332 0)
			(layer "B.Fab")
			(hide yes)
			(effects
				(font
					(size 1 1)
					(thickness 0.15)
				)
				(justify mirror)
			)
		)
		(property "Tolerance" ""
			(at 489.402 332 0)
			(layer "B.Fab")
			(hide yes)
			(effects
				(font
					(size 1 1)
					(thickness 0.15)
				)
				(justify mirror)
			)
		)
		(property "Val" "0R"
			(at 489.402 332 0)
			(layer "B.Fab")
			(hide yes)
			(effects
				(font
					(size 1 1)
					(thickness 0.15)
				)
				(justify mirror)
			)
		)
		(sheetname "HDMI + Ethernet")
		(sheetfile "hdmi-ethernet.kicad_sch")
		(attr smd)
		(fp_rect
			(start -0.925 0.47)
			(end 0.925 -0.47)
			(stroke
				(width 0.05)
				(type default)
			)
			(fill no)
			(layer "B.CrtYd")
		)
		(fp_rect
			(start -0.5 0.25)
			(end 0.5 -0.25)
			(stroke
				(width 0.15)
				(type solid)
			)
			(fill no)
			(layer "B.Fab")
		)
		(pad "1" smd roundrect
			(at -0.48 0 180)
			(size 0.59 0.64)
			(layers "B.Cu" "B.Mask" "B.Paste")
			(roundrect_rratio 0.25)
			(net 12 "Net-(J15A-TRDCT1{slash}2{slash}3{slash}4_1)")
			(pintype "passive")
		)
		(pad "2" smd roundrect
			(at 0.48 0 180)
			(size 0.59 0.64)
			(layers "B.Cu" "B.Mask" "B.Paste")
			(roundrect_rratio 0.25)
			(net 721 "/HDMI + Ethernet/ETH_3V3")
			(pintype "passive")
		)
	)
	(footprint "antmicro-footprints:C_0402_1005Metric"
		(layer "B.Cu")
		(at 159.55 144.5 -90)
		(descr "Capacitor SMD 0402")
		(tags "capacitor SMD 0402")
		(property "Reference" "C171"
			(at -1.9 3.475 90)
			(layer "B.SilkS")
			(effects
				(font
					(size 0.7 0.7)
					(thickness 0.15)
				)
				(justify left bottom mirror)
			)
		)
		(property "Value" "C_100n_0402"
			(at 0 -1.169 90)
			(layer "B.Fab")
			(effects
				(font
					(size 0.7 0.7)
					(thickness 0.15)
				)
				(justify left bottom mirror)
			)
		)
		(property "Description" "SMD Multilayer Ceramic Capacitor, 0.1 µF, 50 V, 0402 [1005 Metric], ± 10%, X5R, GRM Series"
			(at 0 0 270)
			(layer "F.Fab")
			(hide yes)
			(effects
				(font
					(size 1.27 1.27)
					(thickness 0.15)
				)
			)
		)
		(property "Author" "Antmicro"
			(at 15.05 304.05 0)
			(layer "B.Fab")
			(hide yes)
			(effects
				(font
					(size 1 1)
					(thickness 0.15)
				)
				(justify mirror)
			)
		)
		(property "Dielectric" "X5R"
			(at 15.05 304.05 0)
			(layer "B.Fab")
			(hide yes)
			(effects
				(font
					(size 1 1)
					(thickness 0.15)
				)
				(justify mirror)
			)
		)
		(property "License" "Apache-2.0"
			(at 15.05 304.05 0)
			(layer "B.Fab")
			(hide yes)
			(effects
				(font
					(size 1 1)
					(thickness 0.15)
				)
				(justify mirror)
			)
		)
		(property "MPN" "GRM155R61H104KE14D"
			(at 15.05 304.05 0)
			(layer "B.Fab")
			(hide yes)
			(effects
				(font
					(size 1 1)
					(thickness 0.15)
				)
				(justify mirror)
			)
		)
		(property "Manufacturer" "Murata"
			(at 15.05 304.05 0)
			(layer "B.Fab")
			(hide yes)
			(effects
				(font
					(size 1 1)
					(thickness 0.15)
				)
				(justify mirror)
			)
		)
		(property "Val" "100n"
			(at 15.05 304.05 0)
			(layer "B.Fab")
			(hide yes)
			(effects
				(font
					(size 1 1)
					(thickness 0.15)
				)
				(justify mirror)
			)
		)
		(property "Voltage" "50V"
			(at 15.05 304.05 0)
			(layer "B.Fab")
			(hide yes)
			(effects
				(font
					(size 1 1)
					(thickness 0.15)
				)
				(justify mirror)
			)
		)
		(sheetname "DRAM + SRAM")
		(sheetfile "ram.kicad_sch")
		(attr smd)
		(fp_rect
			(start -0.925 0.47)
			(end 0.925 -0.47)
			(stroke
				(width 0.05)
				(type default)
			)
			(fill no)
			(layer "B.CrtYd")
		)
		(fp_line
			(start -0.494 0.25)
			(end 0.504 0.25)
			(stroke
				(width 0.15)
				(type solid)
			)
			(layer "B.Fab")
		)
		(fp_line
			(start 0.504 0.25)
			(end 0.504 -0.248)
			(stroke
				(width 0.15)
				(type solid)
			)
			(layer "B.Fab")
		)
		(fp_line
			(start -0.494 -0.248)
			(end -0.494 0.25)
			(stroke
				(width 0.15)
				(type solid)
			)
			(layer "B.Fab")
		)
		(fp_line
			(start 0.504 -0.248)
			(end -0.494 -0.248)
			(stroke
				(width 0.15)
				(type solid)
			)
			(layer "B.Fab")
		)
		(pad "1" smd roundrect
			(at -0.48 0 270)
			(size 0.59 0.64)
			(layers "B.Cu" "B.Mask" "B.Paste")
			(roundrect_rratio 0.25)
			(net 1 "GND")
			(pintype "passive")
		)
		(pad "2" smd roundrect
			(at 0.48 0 270)
			(size 0.59 0.64)
			(layers "B.Cu" "B.Mask" "B.Paste")
			(roundrect_rratio 0.25)
			(net 7 "+0V675_VTT")
			(pintype "passive")
		)
	)
	(footprint "antmicro-footprints:C_0402_1005Metric"
		(layer "B.Cu")
		(at 167.145001 82.635001 180)
		(descr "Capacitor SMD 0402")
		(tags "capacitor SMD 0402")
		(property "Reference" "C298"
			(at 0.820001 -0.389999 0)
			(layer "B.SilkS")
			(effects
				(font
					(size 0.7 0.7)
					(thickness 0.15)
				)
				(justify left bottom mirror)
			)
		)
		(property "Value" "C_100n_0402"
			(at 0 -1.4 0)
			(layer "B.Fab")
			(effects
				(font
					(size 0.7 0.7)
					(thickness 0.15)
				)
				(justify left bottom mirror)
			)
		)
		(property "Description" "SMD Multilayer Ceramic Capacitor, 0.1 µF, 50 V, 0402 [1005 Metric], ± 10%, X5R, GRM Series"
			(at 0 0 180)
			(layer "F.Fab")
			(hide yes)
			(effects
				(font
					(size 1.27 1.27)
					(thickness 0.15)
				)
			)
		)
		(property "Author" "Antmicro"
			(at 334.290002 165.270002 0)
			(layer "B.Fab")
			(hide yes)
			(effects
				(font
					(size 1 1)
					(thickness 0.15)
				)
				(justify mirror)
			)
		)
		(property "Dielectric" "X5R"
			(at 334.290002 165.270002 0)
			(layer "B.Fab")
			(hide yes)
			(effects
				(font
					(size 1 1)
					(thickness 0.15)
				)
				(justify mirror)
			)
		)
		(property "License" "Apache-2.0"
			(at 334.290002 165.270002 0)
			(layer "B.Fab")
			(hide yes)
			(effects
				(font
					(size 1 1)
					(thickness 0.15)
				)
				(justify mirror)
			)
		)
		(property "MPN" "GRM155R61H104KE14D"
			(at 334.290002 165.270002 0)
			(layer "B.Fab")
			(hide yes)
			(effects
				(font
					(size 1 1)
					(thickness 0.15)
				)
				(justify mirror)
			)
		)
		(property "Manufacturer" "Murata"
			(at 334.290002 165.270002 0)
			(layer "B.Fab")
			(hide yes)
			(effects
				(font
					(size 1 1)
					(thickness 0.15)
				)
				(justify mirror)
			)
		)
		(property "Val" "100n"
			(at 334.290002 165.270002 0)
			(layer "B.Fab")
			(hide yes)
			(effects
				(font
					(size 1 1)
					(thickness 0.15)
				)
				(justify mirror)
			)
		)
		(property "Voltage" "50V"
			(at 334.290002 165.270002 0)
			(layer "B.Fab")
			(hide yes)
			(effects
				(font
					(size 1 1)
					(thickness 0.15)
				)
				(justify mirror)
			)
		)
		(sheetname "FMC+ HSPC")
		(sheetfile "fmc-hspc.kicad_sch")
		(attr smd)
		(fp_rect
			(start -0.925 0.47)
			(end 0.925 -0.47)
			(stroke
				(width 0.05)
				(type default)
			)
			(fill no)
			(layer "B.CrtYd")
		)
		(fp_line
			(start 0.504 0.25)
			(end 0.504 -0.248)
			(stroke
				(width 0.15)
				(type solid)
			)
			(layer "B.Fab")
		)
		(fp_line
			(start 0.504 -0.248)
			(end -0.494 -0.248)
			(stroke
				(width 0.15)
				(type solid)
			)
			(layer "B.Fab")
		)
		(fp_line
			(start -0.494 0.25)
			(end 0.504 0.25)
			(stroke
				(width 0.15)
				(type solid)
			)
			(layer "B.Fab")
		)
		(fp_line
			(start -0.494 -0.248)
			(end -0.494 0.25)
			(stroke
				(width 0.15)
				(type solid)
			)
			(layer "B.Fab")
		)
		(pad "1" smd roundrect
			(at -0.48 0 180)
			(size 0.59 0.64)
			(layers "B.Cu" "B.Mask" "B.Paste")
			(roundrect_rratio 0.25)
			(net 61 "/FMC+ HSPC/GTX116.TX3_P")
			(pintype "passive")
		)
		(pad "2" smd roundrect
			(at 0.48 0 180)
			(size 0.59 0.64)
			(layers "B.Cu" "B.Mask" "B.Paste")
			(roundrect_rratio 0.25)
			(net 60 "/FMC+ HSPC/GTX_TX0_C_P")
			(pintype "passive")
		)
	)
	(footprint "antmicro-footprints:NetTie-2_SMD_Pad0.127mm"
		(layer "B.Cu")
		(at 249.301 148.4 90)
		(descr "Net tie, 2 pin, 0.127mm  SMD pads")
		(tags "net tie")
		(property "Reference" "NT6"
			(at -0.128 1.345 270)
			(layer "B.SilkS")
			(hide yes)
			(effects
				(font
					(size 0.7 0.7)
					(thickness 0.15)
				)
				(justify left bottom mirror)
			)
		)
		(property "Value" "Net-Tie_2"
			(at 0 -1.199 270)
			(layer "B.Fab")
			(effects
				(font
					(size 0.7 0.7)
					(thickness 0.15)
				)
				(justify left bottom mirror)
			)
		)
		(property "Description" "Net tie, 2 pins"
			(at 0 0 90)
			(layer "F.Fab")
			(hide yes)
			(effects
				(font
					(size 1.27 1.27)
					(thickness 0.15)
				)
			)
		)
		(property "Author" "Antmicro"
			(at 397.701 -100.901 0)
			(layer "B.Fab")
			(hide yes)
			(effects
				(font
					(size 1 1)
					(thickness 0.15)
				)
				(justify mirror)
			)
		)
		(property "License" "Apache-2.0"
			(at 397.701 -100.901 0)
			(layer "B.Fab")
			(hide yes)
			(effects
				(font
					(size 1 1)
					(thickness 0.15)
				)
				(justify mirror)
			)
		)
		(property "MPN" ""
			(at 397.701 -100.901 0)
			(layer "B.Fab")
			(hide yes)
			(effects
				(font
					(size 1 1)
					(thickness 0.15)
				)
				(justify mirror)
			)
		)
		(property "Manufacturer" ""
			(at 397.701 -100.901 0)
			(layer "B.Fab")
			(hide yes)
			(effects
				(font
					(size 1 1)
					(thickness 0.15)
				)
				(justify mirror)
			)
		)
		(sheetname "FPGA Config")
		(sheetfile "fpga-config.kicad_sch")
		(attr exclude_from_pos_files)
		(net_tie_pad_groups "1, 2")
		(fp_poly
			(pts
				(xy -0.0635 0.0635) (xy 0.0625 0.0635) (xy 0.0625 -0.0635) (xy -0.0635 -0.0635)
			)
			(stroke
				(width 0)
				(type solid)
			)
			(fill yes)
			(layer "B.Cu")
		)
		(pad "1" smd roundrect
			(at -0.127 0 270)
			(size 0.127 0.127)
			(layers "B.Cu")
			(roundrect_rratio 0.5)
			(chamfer_ratio 0)
			(chamfer top_left bottom_left)
			(net 1315 "/SUP_MCU.DONE")
			(pinfunction "1")
			(pintype "passive")
		)
		(pad "2" smd roundrect
			(at 0.126 0 90)
			(size 0.127 0.127)
			(layers "B.Cu")
			(roundrect_rratio 0.5)
			(chamfer_ratio 0)
			(chamfer top_left bottom_left)
			(net 246 "/FPGA Config/DONE")
			(pinfunction "2")
			(pintype "passive")
		)
	)
	(footprint "antmicro-footprints:R_0402_1005Metric"
		(layer "B.Cu")
		(at 195.691252 93.85 180)
		(descr "Resistor SMD 0402")
		(tags "resistor SMD 0402")
		(property "Reference" "R201"
			(at 0.716252 -0.425 0)
			(layer "B.SilkS")
			(effects
				(font
					(size 0.7 0.7)
					(thickness 0.15)
				)
				(justify left bottom mirror)
			)
		)
		(property "Value" "R_10k_0402"
			(at 0 -1.4 0)
			(layer "B.Fab")
			(effects
				(font
					(size 0.7 0.7)
					(thickness 0.15)
				)
				(justify left bottom mirror)
			)
		)
		(property "Description" "SMD Chip Resistor, 10 kohm, ± 1%, 62.5 mW, 0402 [1005 Metric], Thick Film, General Purpose"
			(at 0 0 180)
			(layer "F.Fab")
			(hide yes)
			(effects
				(font
					(size 1.27 1.27)
					(thickness 0.15)
				)
			)
		)
		(property "Author" "Antmicro"
			(at 391.382504 187.7 0)
			(layer "B.Fab")
			(hide yes)
			(effects
				(font
					(size 1 1)
					(thickness 0.15)
				)
				(justify mirror)
			)
		)
		(property "DNP" "DNP"
			(at 391.382504 187.7 0)
			(layer "B.Fab")
			(hide yes)
			(effects
				(font
					(size 1 1)
					(thickness 0.15)
				)
				(justify mirror)
			)
		)
		(property "License" "Apache-2.0"
			(at 391.382504 187.7 0)
			(layer "B.Fab")
			(hide yes)
			(effects
				(font
					(size 1 1)
					(thickness 0.15)
				)
				(justify mirror)
			)
		)
		(property "MPN" "CR0402-FX-1002GLF"
			(at 391.382504 187.7 0)
			(layer "B.Fab")
			(hide yes)
			(effects
				(font
					(size 1 1)
					(thickness 0.15)
				)
				(justify mirror)
			)
		)
		(property "Manufacturer" "Bourns"
			(at 391.382504 187.7 0)
			(layer "B.Fab")
			(hide yes)
			(effects
				(font
					(size 1 1)
					(thickness 0.15)
				)
				(justify mirror)
			)
		)
		(property "Tolerance" "1%"
			(at 391.382504 187.7 0)
			(layer "B.Fab")
			(hide yes)
			(effects
				(font
					(size 1 1)
					(thickness 0.15)
				)
				(justify mirror)
			)
		)
		(property "Val" "10k"
			(at 391.382504 187.7 0)
			(layer "B.Fab")
			(hide yes)
			(effects
				(font
					(size 1 1)
					(thickness 0.15)
				)
				(justify mirror)
			)
		)
		(property "dnp" ""
			(at 391.382504 187.7 0)
			(layer "B.Fab")
			(hide yes)
			(effects
				(font
					(size 1 1)
					(thickness 0.15)
				)
				(justify mirror)
			)
		)
		(property "exclude_from_bom" ""
			(at 391.382504 187.7 0)
			(layer "B.Fab")
			(hide yes)
			(effects
				(font
					(size 1 1)
					(thickness 0.15)
				)
				(justify mirror)
			)
		)
		(sheetname "HDMI + Ethernet")
		(sheetfile "hdmi-ethernet.kicad_sch")
		(attr smd exclude_from_bom)
		(fp_rect
			(start -0.925 0.47)
			(end 0.925 -0.47)
			(stroke
				(width 0.05)
				(type default)
			)
			(fill no)
			(layer "B.CrtYd")
		)
		(fp_rect
			(start -0.5 0.25)
			(end 0.5 -0.25)
			(stroke
				(width 0.15)
				(type solid)
			)
			(fill no)
			(layer "B.Fab")
		)
		(pad "1" smd roundrect
			(at -0.48 0 180)
			(size 0.59 0.64)
			(layers "B.Cu" "B.Mask" "B.Paste")
			(roundrect_rratio 0.25)
			(net 505 "/FPGA Bank 16 & 17/GBE_RGMII.RXD1")
			(pintype "passive")
		)
		(pad "2" smd roundrect
			(at 0.48 0 180)
			(size 0.59 0.64)
			(layers "B.Cu" "B.Mask" "B.Paste")
			(roundrect_rratio 0.25)
			(net 24 "+3V3")
			(pintype "passive")
		)
	)
	(footprint "antmicro-footprints:R_0402_1005Metric"
		(layer "B.Cu")
		(at 164.75 183.7 -90)
		(descr "Resistor SMD 0402")
		(tags "resistor SMD 0402")
		(property "Reference" "R284"
			(at -3.625 -0.325 90)
			(layer "B.SilkS")
			(effects
				(font
					(size 0.7 0.7)
					(thickness 0.15)
				)
				(justify left bottom mirror)
			)
		)
		(property "Value" "R_47k_0402"
			(at 0 -1.4 90)
			(layer "B.Fab")
			(effects
				(font
					(size 0.7 0.7)
					(thickness 0.15)
				)
				(justify left bottom mirror)
			)
		)
		(property "Description" "SMD Chip Resistor, 47 kohm, ± 1%, 62.5 mW, 0402 [1005 Metric], Thick Film, General Purpose"
			(at 0 0 270)
			(layer "F.Fab")
			(hide yes)
			(effects
				(font
					(size 1.27 1.27)
					(thickness 0.15)
				)
			)
		)
		(property "Author" "Antmicro"
			(at -18.95 348.45 0)
			(layer "B.Fab")
			(hide yes)
			(effects
				(font
					(size 1 1)
					(thickness 0.15)
				)
				(justify mirror)
			)
		)
		(property "License" "Apache-2.0"
			(at -18.95 348.45 0)
			(layer "B.Fab")
			(hide yes)
			(effects
				(font
					(size 1 1)
					(thickness 0.15)
				)
				(justify mirror)
			)
		)
		(property "MPN" "CR0402-FX-4702GLF"
			(at -18.95 348.45 0)
			(layer "B.Fab")
			(hide yes)
			(effects
				(font
					(size 1 1)
					(thickness 0.15)
				)
				(justify mirror)
			)
		)
		(property "Manufacturer" "Bourns"
			(at -18.95 348.45 0)
			(layer "B.Fab")
			(hide yes)
			(effects
				(font
					(size 1 1)
					(thickness 0.15)
				)
				(justify mirror)
			)
		)
		(property "Tolerance" "1%"
			(at -18.95 348.45 0)
			(layer "B.Fab")
			(hide yes)
			(effects
				(font
					(size 1 1)
					(thickness 0.15)
				)
				(justify mirror)
			)
		)
		(property "Val" "47k"
			(at -18.95 348.45 0)
			(layer "B.Fab")
			(hide yes)
			(effects
				(font
					(size 1 1)
					(thickness 0.15)
				)
				(justify mirror)
			)
		)
		(sheetname "DC-DC Converters")
		(sheetfile "dc-dc.kicad_sch")
		(attr smd)
		(fp_rect
			(start -0.925 0.47)
			(end 0.925 -0.47)
			(stroke
				(width 0.05)
				(type default)
			)
			(fill no)
			(layer "B.CrtYd")
		)
		(fp_rect
			(start -0.5 0.25)
			(end 0.5 -0.25)
			(stroke
				(width 0.15)
				(type solid)
			)
			(fill no)
			(layer "B.Fab")
		)
		(pad "1" smd roundrect
			(at -0.48 0 270)
			(size 0.59 0.64)
			(layers "B.Cu" "B.Mask" "B.Paste")
			(roundrect_rratio 0.25)
			(net 1 "GND")
			(pintype "passive")
		)
		(pad "2" smd roundrect
			(at 0.48 0 270)
			(size 0.59 0.64)
			(layers "B.Cu" "B.Mask" "B.Paste")
			(roundrect_rratio 0.25)
			(net 797 "/DC-DC Converters/PB_CTRL_OE")
			(pintype "passive")
		)
	)
)
